(kicad_pcb
	(version 20260206)
	(generator "pcbnew")
	(generator_version "10.0")
	(general
		(thickness 1.6)
		(legacy_teardrops no)
	)
	(paper "A4")
	(title_block
		(title "03242023_DA0F0TMBIJ0_F0T_Motherboard_J_brd_V01_OCP.brd")
		(comment 1 "Grand Teton / footprint 3035 of 6105 (J109), pads 1-48 of 48")
	)
	(layers
		(0 "F.Cu" signal "TOP")
		(4 "In1.Cu" signal "GND")
		(6 "In2.Cu" signal "IN1")
		(8 "In3.Cu" signal "GND1")
		(10 "In4.Cu" signal "IN2")
		(12 "In5.Cu" signal "GND2")
		(14 "In6.Cu" signal "IN3")
		(16 "In7.Cu" signal "GND3")
		(18 "In8.Cu" signal "VCC")
		(20 "In9.Cu" signal "VCC1")
		(22 "In10.Cu" signal "GND4")
		(24 "In11.Cu" signal "IN4")
		(26 "In12.Cu" signal "GND5")
		(28 "In13.Cu" signal "IN5")
		(30 "In14.Cu" signal "GND6")
		(32 "In15.Cu" signal "IN6")
		(34 "In16.Cu" signal "GND7")
		(2 "B.Cu" signal "BOTTOM")
		(9 "F.Adhes" user "F.Adhesive")
		(11 "B.Adhes" user "B.Adhesive")
		(13 "F.Paste" user "Package Geometry/Pastemask Top")
		(15 "B.Paste" user "Package Geometry/Pastemask Bottom")
		(5 "F.SilkS" user "Ref Des/Silkscreen Top")
		(7 "B.SilkS" user "Ref Des/Silkscreen Bottom")
		(1 "F.Mask" user "Board Geometry/Soldermask Top")
		(3 "B.Mask" user "Board Geometry/Soldermask Bottom")
		(17 "Dwgs.User" user "User.Drawings")
		(19 "Cmts.User" user "User.Comments")
		(21 "Eco1.User" user "User.Eco1")
		(23 "Eco2.User" user "User.Eco2")
		(25 "Edge.Cuts" user "Board Geometry/Outline")
		(27 "Margin" user)
		(31 "F.CrtYd" user "Package Geometry/Place Bound Top")
		(29 "B.CrtYd" user "Package Geometry/Place Bound Bottom")
		(35 "F.Fab" user "Ref Des/Assembly Top")
		(33 "B.Fab" user "Ref Des/Assembly Bottom")
	)
	(footprint ""
		(layer "F.Cu")
		(at 142.750032 -440.489848)
		(property "Reference" "J109"
			(at 1.4859 23.131272 0)
			(unlocked yes)
			(layer "F.SilkS")
			(effects
				(font
					(size 0.7874 0.5842)
					(thickness 0.1524)
				)
				(justify left)
			)
		)
		(property "Value" ""
			(at 0 0 0)
			(layer "F.Fab")
			(effects
				(font
					(size 1.27 1.27)
				)
			)
		)
		(duplicate_pad_numbers_are_jumpers no)
		(pad "A1" thru_hole rect
			(at 0 0 180)
			(size 0.766318 0.766318)
			(drill 0.359918)
			(layers "*.Cu" "*.Mask")
			(remove_unused_layers no)
			(net "BMC_MONITER_BUF")
			(clearance 0.0508)
			(thermal_gap 0.0508)
			(padstack
				(mode front_inner_back)
				(layer "Inner"
					(shape circle)
					(size 0.766318 0.766318)
					(clearance 0.0508)
				)
				(layer "B.Cu"
					(shape rect)
					(size 0.766318 0.766318)
					(clearance 0.0508)
				)
			)
		)
		(pad "A2" thru_hole circle
			(at 1.999996 0.199898 180)
			(size 0.906272 0.906272)
			(drill 0.499872)
			(layers "*.Cu" "*.Mask")
			(remove_unused_layers no)
			(net "GND")
			(clearance 0.0508)
			(thermal_gap 0.0508)
		)
		(pad "A3" thru_hole circle
			(at 3.999992 0 180)
			(size 0.766318 0.766318)
			(drill 0.359918)
			(layers "*.Cu" "*.Mask")
			(remove_unused_layers no)
			(net "BIC_MONITER")
			(clearance 0.0508)
			(thermal_gap 0.0508)
		)
		(pad "A4" thru_hole circle
			(at 5.999988 0.199898 180)
			(size 0.906272 0.906272)
			(drill 0.499872)
			(layers "*.Cu" "*.Mask")
			(remove_unused_layers no)
			(net "GND")
			(clearance 0.0508)
			(thermal_gap 0.0508)
		)
		(pad "A5" thru_hole circle
			(at 7.999984 0 180)
			(size 0.766318 0.766318)
			(drill 0.359918)
			(layers "*.Cu" "*.Mask")
			(remove_unused_layers no)
			(net "SMB_BMC_SWB_BUF_SCL")
			(clearance 0.0508)
			(thermal_gap 0.0508)
		)
		(pad "A6" thru_hole circle
			(at 9.99998 0.199898 180)
			(size 0.906272 0.906272)
			(drill 0.499872)
			(layers "*.Cu" "*.Mask")
			(remove_unused_layers no)
			(net "GND")
			(clearance 0.0508)
			(thermal_gap 0.0508)
		)
		(pad "A7" thru_hole circle
			(at 11.999976 0 180)
			(size 0.766318 0.766318)
			(drill 0.359918)
			(layers "*.Cu" "*.Mask")
			(remove_unused_layers no)
			(net "SMB_BMC_SWB_BUF_SDA")
			(clearance 0.0508)
			(thermal_gap 0.0508)
		)
		(pad "A8" thru_hole circle
			(at 13.999972 0.199898 180)
			(size 0.906272 0.906272)
			(drill 0.499872)
			(layers "*.Cu" "*.Mask")
			(remove_unused_layers no)
			(net "GND")
			(clearance 0.0508)
			(thermal_gap 0.0508)
		)
		(pad "B1" thru_hole circle
			(at 0 1.199896 180)
			(size 0.906272 0.906272)
			(drill 0.499872)
			(layers "*.Cu" "*.Mask")
			(remove_unused_layers no)
			(net "GND")
			(clearance 0.0508)
			(thermal_gap 0.0508)
		)
		(pad "B3" thru_hole circle
			(at 3.999992 1.199896 180)
			(size 0.906272 0.906272)
			(drill 0.499872)
			(layers "*.Cu" "*.Mask")
			(remove_unused_layers no)
			(net "GND")
			(clearance 0.0508)
			(thermal_gap 0.0508)
		)
		(pad "B5" thru_hole circle
			(at 7.999984 1.199896 180)
			(size 0.906272 0.906272)
			(drill 0.499872)
			(layers "*.Cu" "*.Mask")
			(remove_unused_layers no)
			(net "GND")
			(clearance 0.0508)
			(thermal_gap 0.0508)
		)
		(pad "B7" thru_hole circle
			(at 11.999976 1.199896 180)
			(size 0.906272 0.906272)
			(drill 0.499872)
			(layers "*.Cu" "*.Mask")
			(remove_unused_layers no)
			(net "GND")
			(clearance 0.0508)
			(thermal_gap 0.0508)
		)
		(pad "D2" thru_hole circle
			(at 1.999996 3.800094 180)
			(size 0.906272 0.906272)
			(drill 0.499872)
			(layers "*.Cu" "*.Mask")
			(remove_unused_layers no)
			(net "GND")
			(clearance 0.0508)
			(thermal_gap 0.0508)
		)
		(pad "D4" thru_hole circle
			(at 5.999988 3.800094 180)
			(size 0.906272 0.906272)
			(drill 0.499872)
			(layers "*.Cu" "*.Mask")
			(remove_unused_layers no)
			(net "GND")
			(clearance 0.0508)
			(thermal_gap 0.0508)
		)
		(pad "D6" thru_hole circle
			(at 9.99998 3.800094 180)
			(size 0.906272 0.906272)
			(drill 0.499872)
			(layers "*.Cu" "*.Mask")
			(remove_unused_layers no)
			(net "GND")
			(clearance 0.0508)
			(thermal_gap 0.0508)
		)
		(pad "D8" thru_hole circle
			(at 13.999972 3.800094 180)
			(size 0.906272 0.906272)
			(drill 0.499872)
			(layers "*.Cu" "*.Mask")
			(remove_unused_layers no)
			(net "GND")
			(clearance 0.0508)
			(thermal_gap 0.0508)
		)
		(pad "E1" thru_hole circle
			(at 0 4.800092 180)
			(size 0.906272 0.906272)
			(drill 0.499872)
			(layers "*.Cu" "*.Mask")
			(remove_unused_layers no)
			(net "GND")
			(clearance 0.0508)
			(thermal_gap 0.0508)
		)
		(pad "E3" thru_hole circle
			(at 3.999992 4.800092 180)
			(size 0.906272 0.906272)
			(drill 0.499872)
			(layers "*.Cu" "*.Mask")
			(remove_unused_layers no)
			(net "GND")
			(clearance 0.0508)
			(thermal_gap 0.0508)
		)
		(pad "E5" thru_hole circle
			(at 7.999984 4.800092 180)
			(size 0.906272 0.906272)
			(drill 0.499872)
			(layers "*.Cu" "*.Mask")
			(remove_unused_layers no)
			(net "GND")
			(clearance 0.0508)
			(thermal_gap 0.0508)
		)
		(pad "E7" thru_hole circle
			(at 11.999976 4.800092 180)
			(size 0.906272 0.906272)
			(drill 0.499872)
			(layers "*.Cu" "*.Mask")
			(remove_unused_layers no)
			(net "GND")
			(clearance 0.0508)
			(thermal_gap 0.0508)
		)
		(pad "G2" thru_hole circle
			(at 1.999996 7.400036 180)
			(size 0.906272 0.906272)
			(drill 0.499872)
			(layers "*.Cu" "*.Mask")
			(remove_unused_layers no)
			(net "GND")
			(clearance 0.0508)
			(thermal_gap 0.0508)
		)
		(pad "G4" thru_hole circle
			(at 5.999988 7.400036 180)
			(size 0.906272 0.906272)
			(drill 0.499872)
			(layers "*.Cu" "*.Mask")
			(remove_unused_layers no)
			(net "GND")
			(clearance 0.0508)
			(thermal_gap 0.0508)
		)
		(pad "G6" thru_hole circle
			(at 9.99998 7.400036 180)
			(size 0.906272 0.906272)
			(drill 0.499872)
			(layers "*.Cu" "*.Mask")
			(remove_unused_layers no)
			(net "GND")
			(clearance 0.0508)
			(thermal_gap 0.0508)
		)
		(pad "G8" thru_hole circle
			(at 13.999972 7.400036 180)
			(size 0.906272 0.906272)
			(drill 0.499872)
			(layers "*.Cu" "*.Mask")
			(remove_unused_layers no)
			(net "GND")
			(clearance 0.0508)
			(thermal_gap 0.0508)
		)
		(pad "H1" thru_hole circle
			(at 0 8.400034 180)
			(size 0.906272 0.906272)
			(drill 0.499872)
			(layers "*.Cu" "*.Mask")
			(remove_unused_layers no)
			(net "GND")
			(clearance 0.0508)
			(thermal_gap 0.0508)
		)
		(pad "H3" thru_hole circle
			(at 3.999992 8.400034 180)
			(size 0.906272 0.906272)
			(drill 0.499872)
			(layers "*.Cu" "*.Mask")
			(remove_unused_layers no)
			(net "GND")
			(clearance 0.0508)
			(thermal_gap 0.0508)
		)
		(pad "H5" thru_hole circle
			(at 7.999984 8.400034 180)
			(size 0.906272 0.906272)
			(drill 0.499872)
			(layers "*.Cu" "*.Mask")
			(remove_unused_layers no)
			(net "GND")
			(clearance 0.0508)
			(thermal_gap 0.0508)
		)
		(pad "H7" thru_hole circle
			(at 11.999976 8.400034 180)
			(size 0.906272 0.906272)
			(drill 0.499872)
			(layers "*.Cu" "*.Mask")
			(remove_unused_layers no)
			(net "GND")
			(clearance 0.0508)
			(thermal_gap 0.0508)
		)
		(pad "J2" thru_hole circle
			(at 1.999996 10.999978 180)
			(size 0.906272 0.906272)
			(drill 0.499872)
			(layers "*.Cu" "*.Mask")
			(remove_unused_layers no)
			(net "GND")
			(clearance 0.0508)
			(thermal_gap 0.0508)
		)
		(pad "J4" thru_hole circle
			(at 5.999988 10.999978 180)
			(size 0.906272 0.906272)
			(drill 0.499872)
			(layers "*.Cu" "*.Mask")
			(remove_unused_layers no)
			(net "GND")
			(clearance 0.0508)
			(thermal_gap 0.0508)
		)
		(pad "J6" thru_hole circle
			(at 9.99998 10.999978 180)
			(size 0.906272 0.906272)
			(drill 0.499872)
			(layers "*.Cu" "*.Mask")
			(remove_unused_layers no)
			(net "GND")
			(clearance 0.0508)
			(thermal_gap 0.0508)
		)
		(pad "J8" thru_hole circle
			(at 13.999972 10.999978 180)
			(size 0.906272 0.906272)
			(drill 0.499872)
			(layers "*.Cu" "*.Mask")
			(remove_unused_layers no)
			(net "GND")
			(clearance 0.0508)
			(thermal_gap 0.0508)
		)
		(pad "K1" thru_hole circle
			(at 0 11.999976 180)
			(size 0.906272 0.906272)
			(drill 0.499872)
			(layers "*.Cu" "*.Mask")
			(remove_unused_layers no)
			(net "GND")
			(clearance 0.0508)
			(thermal_gap 0.0508)
		)
		(pad "K3" thru_hole circle
			(at 3.999992 11.999976 180)
			(size 0.906272 0.906272)
			(drill 0.499872)
			(layers "*.Cu" "*.Mask")
			(remove_unused_layers no)
			(net "GND")
			(clearance 0.0508)
			(thermal_gap 0.0508)
		)
		(pad "K5" thru_hole circle
			(at 7.999984 11.999976 180)
			(size 0.906272 0.906272)
			(drill 0.499872)
			(layers "*.Cu" "*.Mask")
			(remove_unused_layers no)
			(net "GND")
			(clearance 0.0508)
			(thermal_gap 0.0508)
		)
		(pad "K7" thru_hole circle
			(at 11.999976 11.999976 180)
			(size 0.906272 0.906272)
			(drill 0.499872)
			(layers "*.Cu" "*.Mask")
			(remove_unused_layers no)
			(net "GND")
			(clearance 0.0508)
			(thermal_gap 0.0508)
		)
		(pad "M2" thru_hole circle
			(at 1.999996 14.59992 180)
			(size 0.906272 0.906272)
			(drill 0.499872)
			(layers "*.Cu" "*.Mask")
			(remove_unused_layers no)
			(net "GND")
			(clearance 0.0508)
			(thermal_gap 0.0508)
		)
		(pad "M4" thru_hole circle
			(at 5.999988 14.59992 180)
			(size 0.906272 0.906272)
			(drill 0.499872)
			(layers "*.Cu" "*.Mask")
			(remove_unused_layers no)
			(net "GND")
			(clearance 0.0508)
			(thermal_gap 0.0508)
		)
		(pad "M6" thru_hole circle
			(at 9.99998 14.59992 180)
			(size 0.906272 0.906272)
			(drill 0.499872)
			(layers "*.Cu" "*.Mask")
			(remove_unused_layers no)
			(net "GND")
			(clearance 0.0508)
			(thermal_gap 0.0508)
		)
		(pad "M8" thru_hole circle
			(at 13.999972 14.59992 180)
			(size 0.906272 0.906272)
			(drill 0.499872)
			(layers "*.Cu" "*.Mask")
			(remove_unused_layers no)
			(net "GND")
			(clearance 0.0508)
			(thermal_gap 0.0508)
		)
		(pad "N1" thru_hole circle
			(at 0 15.599918 180)
			(size 0.906272 0.906272)
			(drill 0.499872)
			(layers "*.Cu" "*.Mask")
			(remove_unused_layers no)
			(net "GND")
			(clearance 0.0508)
			(thermal_gap 0.0508)
		)
		(pad "N2" thru_hole circle
			(at 1.999996 15.80007 180)
			(size 0.766318 0.766318)
			(drill 0.359918)
			(layers "*.Cu" "*.Mask")
			(remove_unused_layers no)
			(net "GPU_FPGA_EROT_FATALERR_N")
			(clearance 0.0508)
			(thermal_gap 0.0508)
		)
		(pad "N3" thru_hole circle
			(at 3.999992 15.599918 180)
			(size 0.906272 0.906272)
			(drill 0.499872)
			(layers "*.Cu" "*.Mask")
			(remove_unused_layers no)
			(net "GND")
			(clearance 0.0508)
			(thermal_gap 0.0508)
		)
		(pad "N4" thru_hole circle
			(at 5.999988 15.80007 180)
			(size 0.766318 0.766318)
			(drill 0.359918)
			(layers "*.Cu" "*.Mask")
			(remove_unused_layers no)
			(net "GPU_3V3IO_RSVD0_FFU")
			(clearance 0.0508)
			(thermal_gap 0.0508)
		)
		(pad "N5" thru_hole circle
			(at 7.999984 15.599918 180)
			(size 0.906272 0.906272)
			(drill 0.499872)
			(layers "*.Cu" "*.Mask")
			(remove_unused_layers no)
			(net "GND")
			(clearance 0.0508)
			(thermal_gap 0.0508)
		)
		(pad "N6" thru_hole circle
			(at 9.99998 15.80007 180)
			(size 0.766318 0.766318)
			(drill 0.359918)
			(layers "*.Cu" "*.Mask")
			(remove_unused_layers no)
			(net "GPU_3V3IO_RSVD1_FFU")
			(clearance 0.0508)
			(thermal_gap 0.0508)
		)
		(pad "N7" thru_hole circle
			(at 11.999976 15.599918 180)
			(size 0.906272 0.906272)
			(drill 0.499872)
			(layers "*.Cu" "*.Mask")
			(remove_unused_layers no)
			(net "GND")
			(clearance 0.0508)
			(thermal_gap 0.0508)
		)
		(pad "N8" thru_hole circle
			(at 13.999972 15.80007 180)
			(size 0.766318 0.766318)
			(drill 0.359918)
			(layers "*.Cu" "*.Mask")
			(remove_unused_layers no)
			(net "PRSNT_CABLE_GPU_B3_N")
			(clearance 0.0508)
			(thermal_gap 0.0508)
		)
	)
)
